(kicad_pcb
	(version 20241229)
	(generator "pcbnew")
	(generator_version "9.0")
	(general
		(thickness 1.6642)
		(legacy_teardrops no)
	)
	(paper "A3")
	(title_block
		(title "PolarFire SoM")
		(date "2025-07-22")
		(rev "1.1.4")
		(company "Antmicro Ltd")
		(comment 1 "www.antmicro.com")
		(comment 9 "footprints 45-48 of 470")
	)
	(layers
		(0 "F.Cu" mixed)
		(4 "In1.Cu" power)
		(6 "In2.Cu" signal)
		(8 "In3.Cu" power)
		(10 "In4.Cu" signal)
		(12 "In5.Cu" power)
		(14 "In6.Cu" power)
		(16 "In7.Cu" signal)
		(18 "In8.Cu" power)
		(20 "In9.Cu" signal)
		(22 "In10.Cu" power)
		(24 "In11.Cu" signal)
		(26 "In12.Cu" signal)
		(2 "B.Cu" mixed)
		(9 "F.Adhes" user "F.Adhesive")
		(11 "B.Adhes" user "B.Adhesive")
		(13 "F.Paste" user)
		(15 "B.Paste" user)
		(5 "F.SilkS" user "F.Silkscreen")
		(7 "B.SilkS" user "B.Silkscreen")
		(1 "F.Mask" user)
		(3 "B.Mask" user)
		(17 "Dwgs.User" user "User.Drawings")
		(19 "Cmts.User" user "User.Comments")
		(21 "Eco1.User" user "User.Eco1")
		(23 "Eco2.User" user "User.Eco2")
		(25 "Edge.Cuts" user)
		(27 "Margin" user)
		(31 "F.CrtYd" user "F.Courtyard")
		(29 "B.CrtYd" user "B.Courtyard")
		(35 "F.Fab" user)
		(33 "B.Fab" user)
	)
	(footprint "antmicro-footprints:L_Coilcraft-XEL4020"
		(layer "F.Cu")
		(at 187.784404 151.354531 90)
		(property "Reference" "L1"
			(at -3.265469 1.175596 180)
			(layer "F.SilkS")
			(effects
				(font
					(size 0.7 0.7)
					(thickness 0.15)
				)
				(justify left bottom)
			)
		)
		(property "Value" "L_1u5_7.5A_Coilcraft-XEL4020"
			(at 0 3.35 90)
			(layer "F.Fab")
			(hide yes)
			(effects
				(font
					(size 0.7 0.7)
					(thickness 0.15)
				)
				(justify left bottom)
			)
		)
		(property "Datasheet" "https://www.coilcraft.com/getmedia/3c7caaa2-c1ed-4ff8-84e5-0b1b14a30417/xel4020.pdf"
			(at 0 0 90)
			(layer "F.Fab")
			(hide yes)
			(effects
				(font
					(size 1.27 1.27)
					(thickness 0.15)
				)
			)
		)
		(property "Description" "Power Inductor (SMT), 1.5 µH, 7.5 A, Shielded, 7.4 A, XEL4020-152MEC"
			(at 0 0 90)
			(layer "F.Fab")
			(hide yes)
			(effects
				(font
					(size 1.27 1.27)
					(thickness 0.15)
				)
			)
		)
		(property "Author" "Antmicro"
			(at 339.138935 -36.429873 0)
			(layer "F.Fab")
			(hide yes)
			(effects
				(font
					(size 1 1)
					(thickness 0.15)
				)
			)
		)
		(property "IMax" "7.5 A"
			(at 339.138935 -36.429873 0)
			(layer "F.Fab")
			(hide yes)
			(effects
				(font
					(size 1 1)
					(thickness 0.15)
				)
			)
		)
		(property "ISat" "7.4 A"
			(at 339.138935 -36.429873 0)
			(layer "F.Fab")
			(hide yes)
			(effects
				(font
					(size 1 1)
					(thickness 0.15)
				)
			)
		)
		(property "License" "Apache-2.0"
			(at 339.138935 -36.429873 0)
			(layer "F.Fab")
			(hide yes)
			(effects
				(font
					(size 1 1)
					(thickness 0.15)
				)
			)
		)
		(property "MPN" "XEL4020-152MEC "
			(at 339.138935 -36.429873 0)
			(layer "F.Fab")
			(hide yes)
			(effects
				(font
					(size 1 1)
					(thickness 0.15)
				)
			)
		)
		(property "Manufacturer" "Coilcraft"
			(at 339.138935 -36.429873 0)
			(layer "F.Fab")
			(hide yes)
			(effects
				(font
					(size 1 1)
					(thickness 0.15)
				)
			)
		)
		(property "Public" ""
			(at 339.138935 -36.429873 0)
			(layer "F.Fab")
			(hide yes)
			(effects
				(font
					(size 1 1)
					(thickness 0.15)
				)
			)
		)
		(property "Size" "4x4"
			(at 339.138935 -36.429873 0)
			(layer "F.Fab")
			(hide yes)
			(effects
				(font
					(size 1 1)
					(thickness 0.15)
				)
			)
		)
		(property "Val" "1u5/7.5A"
			(at 339.138935 -36.429873 0)
			(layer "F.Fab")
			(hide yes)
			(effects
				(font
					(size 1 1)
					(thickness 0.15)
				)
			)
		)
		(sheetname "/Supply/")
		(sheetfile "supply.kicad_sch")
		(attr smd)
		(fp_line
			(start -2.2 -2.2)
			(end 2.2 -2.2)
			(stroke
				(width 0.15)
				(type solid)
			)
			(layer "F.SilkS")
		)
		(fp_line
			(start 2.2 2.2)
			(end 2.2 -2.2)
			(stroke
				(width 0.15)
				(type solid)
			)
			(layer "F.SilkS")
		)
		(fp_line
			(start -2.2 2.2)
			(end -2.2 -2.2)
			(stroke
				(width 0.15)
				(type solid)
			)
			(layer "F.SilkS")
		)
		(fp_line
			(start -2.2 2.2)
			(end 2.2 2.2)
			(stroke
				(width 0.15)
				(type solid)
			)
			(layer "F.SilkS")
		)
		(fp_rect
			(start -2.4 -2.4)
			(end 2.4 2.4)
			(stroke
				(width 0.05)
				(type solid)
			)
			(fill no)
			(layer "F.CrtYd")
		)
		(fp_rect
			(start -2.15 -2.15)
			(end 2.15 2.15)
			(stroke
				(width 0.15)
				(type solid)
			)
			(fill no)
			(layer "F.Fab")
		)
		(fp_text user "Author: Antmicro"
			(at -2.4 5.35 90)
			(layer "F.Fab")
			(effects
				(font
					(size 0.7 0.7)
					(thickness 0.15)
				)
				(justify left bottom)
			)
		)
		(fp_text user "License: Apache-2.0"
			(at -2.4 7.75 90)
			(layer "F.Fab")
			(effects
				(font
					(size 0.7 0.7)
					(thickness 0.15)
				)
				(justify left bottom)
			)
		)
		(fp_text user "${REFERENCE}"
			(at -2.4 6.55 90)
			(layer "F.Fab")
			(effects
				(font
					(size 0.7 0.7)
					(thickness 0.15)
				)
				(justify left bottom)
			)
		)
		(pad "1" smd roundrect
			(at -1.185 0 90)
			(size 0.98 3.4)
			(layers "F.Cu" "F.Mask" "F.Paste")
			(roundrect_rratio 0.1)
			(net 150 "/Supply/1V05_SW")
			(pintype "passive")
		)
		(pad "2" smd roundrect
			(at 1.185 0 90)
			(size 0.98 3.4)
			(layers "F.Cu" "F.Mask" "F.Paste")
			(roundrect_rratio 0.1)
			(net 522 "/Supply/1V05_REG")
			(pintype "passive")
		)
	)
	(footprint "antmicro-footprints:R_0402_1005Metric"
		(layer "F.Cu")
		(at 198.762486 117.687335 180)
		(descr "Resistor SMD 0402")
		(tags "resistor SMD 0402")
		(property "Reference" "R13"
			(at 1.092486 0.697335 180)
			(layer "F.SilkS")
			(effects
				(font
					(size 0.7 0.7)
					(thickness 0.15)
				)
				(justify left bottom)
			)
		)
		(property "Value" "R_10k_0402"
			(at -1.011843 1.772047 180)
			(layer "F.Fab")
			(hide yes)
			(effects
				(font
					(size 0.7 0.7)
					(thickness 0.15)
				)
				(justify left bottom)
			)
		)
		(property "Datasheet" "https://www.bourns.com/docs/product-datasheets/cr.pdf"
			(at 0 0 180)
			(layer "F.Fab")
			(hide yes)
			(effects
				(font
					(size 1.27 1.27)
					(thickness 0.15)
				)
			)
		)
		(property "Description" "SMD Chip Resistor, 10 kohm, ± 1%, 62.5 mW, 0402 [1005 Metric], Thick Film, General Purpose"
			(at 0 0 180)
			(layer "F.Fab")
			(hide yes)
			(effects
				(font
					(size 1.27 1.27)
					(thickness 0.15)
				)
			)
		)
		(property "Author" "Antmicro"
			(at 397.524972 235.37467 0)
			(layer "F.Fab")
			(hide yes)
			(effects
				(font
					(size 1 1)
					(thickness 0.15)
				)
			)
		)
		(property "License" "Apache-2.0"
			(at 397.524972 235.37467 0)
			(layer "F.Fab")
			(hide yes)
			(effects
				(font
					(size 1 1)
					(thickness 0.15)
				)
			)
		)
		(property "MPN" "CR0402-FX-1002GLF"
			(at 397.524972 235.37467 0)
			(layer "F.Fab")
			(hide yes)
			(effects
				(font
					(size 1 1)
					(thickness 0.15)
				)
			)
		)
		(property "Manufacturer" "Bourns"
			(at 397.524972 235.37467 0)
			(layer "F.Fab")
			(hide yes)
			(effects
				(font
					(size 1 1)
					(thickness 0.15)
				)
			)
		)
		(property "Public" ""
			(at 397.524972 235.37467 0)
			(layer "F.Fab")
			(hide yes)
			(effects
				(font
					(size 1 1)
					(thickness 0.15)
				)
			)
		)
		(property "Tolerance" "1%"
			(at 397.524972 235.37467 0)
			(layer "F.Fab")
			(hide yes)
			(effects
				(font
					(size 1 1)
					(thickness 0.15)
				)
			)
		)
		(property "Val" "10k"
			(at 397.524972 235.37467 0)
			(layer "F.Fab")
			(hide yes)
			(effects
				(font
					(size 1 1)
					(thickness 0.15)
				)
			)
		)
		(sheetname "/Top Connector/")
		(sheetfile "top-connector.kicad_sch")
		(attr smd)
		(fp_rect
			(start -0.925 -0.47)
			(end 0.925 0.47)
			(stroke
				(width 0.05)
				(type default)
			)
			(fill no)
			(layer "F.CrtYd")
		)
		(fp_rect
			(start -0.5 -0.25)
			(end 0.5 0.25)
			(stroke
				(width 0.15)
				(type solid)
			)
			(fill no)
			(layer "F.Fab")
		)
		(fp_text user "${REFERENCE}"
			(at -0.95 3.168 180)
			(layer "F.Fab")
			(effects
				(font
					(size 0.7 0.7)
					(thickness 0.15)
				)
				(justify left bottom)
			)
		)
		(fp_text user "License: Apache-2.0"
			(at -0.95 5.169 180)
			(layer "F.Fab")
			(effects
				(font
					(size 0.7 0.7)
					(thickness 0.15)
				)
				(justify left bottom)
			)
		)
		(fp_text user "Author: Antmicro"
			(at -0.95 4.169 180)
			(layer "F.Fab")
			(effects
				(font
					(size 0.7 0.7)
					(thickness 0.15)
				)
				(justify left bottom)
			)
		)
		(pad "1" smd roundrect
			(at -0.48 0 180)
			(size 0.59 0.64)
			(layers "F.Cu" "F.Mask" "F.Paste")
			(roundrect_rratio 0.25)
			(net 28 "GPIO17")
			(pintype "passive")
		)
		(pad "2" smd roundrect
			(at 0.48 0 180)
			(size 0.59 0.64)
			(layers "F.Cu" "F.Mask" "F.Paste")
			(roundrect_rratio 0.25)
			(net 245 "Net-(J1-Pad50)")
			(pintype "passive")
		)
	)
	(footprint "antmicro-footprints:C_Pol_EIA-B"
		(layer "F.Cu")
		(at 189.1855 145.039)
		(property "Reference" "C60"
			(at -2.123 -1.676 0)
			(layer "F.SilkS")
			(effects
				(font
					(size 0.7 0.7)
					(thickness 0.15)
				)
				(justify left bottom)
			)
		)
		(property "Value" "C_Pol_330u_6.3V_KEMET-T520-B"
			(at 0 2.85 0)
			(layer "F.Fab")
			(hide yes)
			(effects
				(font
					(size 0.7 0.7)
					(thickness 0.15)
				)
				(justify left bottom)
			)
		)
		(property "Datasheet" "https://www.kemet.com/en/us/capacitors/product/T520B337M006ATE040.html"
			(at 0 0 0)
			(layer "F.Fab")
			(hide yes)
			(effects
				(font
					(size 1.27 1.27)
					(thickness 0.15)
				)
			)
		)
		(property "Description" "Tantalum Polymer Capacitor, KO-CAP®, 330 µF, ± 20%, 6.3 V, B, 0.04 ohm, 1411 [3528 Metric]"
			(at 0 0 0)
			(layer "F.Fab")
			(hide yes)
			(effects
				(font
					(size 1.27 1.27)
					(thickness 0.15)
				)
			)
		)
		(property "Author" "Antmicro"
			(at 0 0 0)
			(layer "F.Fab")
			(hide yes)
			(effects
				(font
					(size 1 1)
					(thickness 0.15)
				)
			)
		)
		(property "Capacitance" "330u"
			(at 0 0 0)
			(layer "F.Fab")
			(hide yes)
			(effects
				(font
					(size 1 1)
					(thickness 0.15)
				)
			)
		)
		(property "Dielectric" "template_dielectric"
			(at 0 0 0)
			(layer "F.Fab")
			(hide yes)
			(effects
				(font
					(size 1 1)
					(thickness 0.15)
				)
			)
		)
		(property "License" "Apache-2.0"
			(at 0 0 0)
			(layer "F.Fab")
			(hide yes)
			(effects
				(font
					(size 1 1)
					(thickness 0.15)
				)
			)
		)
		(property "MPN" "T520B337M006ATE040"
			(at 0 0 0)
			(layer "F.Fab")
			(hide yes)
			(effects
				(font
					(size 1 1)
					(thickness 0.15)
				)
			)
		)
		(property "Manufacturer" "KEMET"
			(at 0 0 0)
			(layer "F.Fab")
			(hide yes)
			(effects
				(font
					(size 1 1)
					(thickness 0.15)
				)
			)
		)
		(property "Public" ""
			(at 0 0 0)
			(layer "F.Fab")
			(hide yes)
			(effects
				(font
					(size 1 1)
					(thickness 0.15)
				)
			)
		)
		(property "Val" "330u"
			(at 0 0 0)
			(layer "F.Fab")
			(hide yes)
			(effects
				(font
					(size 1 1)
					(thickness 0.15)
				)
			)
		)
		(property "Voltage" "6.3V"
			(at 0 0 0)
			(layer "F.Fab")
			(hide yes)
			(effects
				(font
					(size 1 1)
					(thickness 0.15)
				)
			)
		)
		(sheetname "/FPGA Supply/")
		(sheetfile "fpga-supply.kicad_sch")
		(attr smd)
		(fp_line
			(start -2.521 -1.676)
			(end -2.123 -1.676)
			(stroke
				(width 0.15)
				(type solid)
			)
			(layer "F.SilkS")
		)
		(fp_line
			(start -2.325 -1.475)
			(end -2.325 -1.878)
			(stroke
				(width 0.15)
				(type solid)
			)
			(layer "F.SilkS")
		)
		(fp_line
			(start -1.8 -1.6)
			(end 1.8 -1.6)
			(stroke
				(width 0.15)
				(type solid)
			)
			(layer "F.SilkS")
		)
		(fp_line
			(start -1.8 -1.3)
			(end -1.8 -1.6)
			(stroke
				(width 0.15)
				(type solid)
			)
			(layer "F.SilkS")
		)
		(fp_line
			(start -1.8 1.3)
			(end -1.8 1.6)
			(stroke
				(width 0.15)
				(type solid)
			)
			(layer "F.SilkS")
		)
		(fp_line
			(start 1.8 -1.3)
			(end 1.8 -1.6)
			(stroke
				(width 0.15)
				(type solid)
			)
			(layer "F.SilkS")
		)
		(fp_line
			(start 1.8 1.3)
			(end 1.8 1.6)
			(stroke
				(width 0.15)
				(type solid)
			)
			(layer "F.SilkS")
		)
		(fp_line
			(start 1.8 1.6)
			(end -1.8 1.6)
			(stroke
				(width 0.15)
				(type solid)
			)
			(layer "F.SilkS")
		)
		(fp_line
			(start -2.411 -1.35)
			(end -2.41 1.35)
			(stroke
				(width 0.05)
				(type solid)
			)
			(layer "F.CrtYd")
		)
		(fp_line
			(start -1.97 -1.75)
			(end -1.97 -1.35)
			(stroke
				(width 0.05)
				(type solid)
			)
			(layer "F.CrtYd")
		)
		(fp_line
			(start -1.97 -1.35)
			(end -2.41 -1.35)
			(stroke
				(width 0.05)
				(type solid)
			)
			(layer "F.CrtYd")
		)
		(fp_line
			(start -1.97 1.35)
			(end -2.41 1.35)
			(stroke
				(width 0.05)
				(type solid)
			)
			(layer "F.CrtYd")
		)
		(fp_line
			(start -1.97 1.35)
			(end -1.97 1.75)
			(stroke
				(width 0.05)
				(type solid)
			)
			(layer "F.CrtYd")
		)
		(fp_line
			(start 1.959 -1.75)
			(end -1.97 -1.75)
			(stroke
				(width 0.05)
				(type solid)
			)
			(layer "F.CrtYd")
		)
		(fp_line
			(start 1.959 -1.75)
			(end 1.959 -1.35)
			(stroke
				(width 0.05)
				(type solid)
			)
			(layer "F.CrtYd")
		)
		(fp_line
			(start 1.96 1.35)
			(end 1.96 1.75)
			(stroke
				(width 0.05)
				(type solid)
			)
			(layer "F.CrtYd")
		)
		(fp_line
			(start 1.96 1.75)
			(end -1.97 1.75)
			(stroke
				(width 0.05)
				(type solid)
			)
			(layer "F.CrtYd")
		)
		(fp_line
			(start 2.399 -1.35)
			(end 1.959 -1.35)
			(stroke
				(width 0.05)
				(type solid)
			)
			(layer "F.CrtYd")
		)
		(fp_line
			(start 2.399 -1.35)
			(end 2.4 1.35)
			(stroke
				(width 0.05)
				(type solid)
			)
			(layer "F.CrtYd")
		)
		(fp_line
			(start 2.4 1.35)
			(end 1.96 1.35)
			(stroke
				(width 0.05)
				(type solid)
			)
			(layer "F.CrtYd")
		)
		(fp_line
			(start -1.7 1.324)
			(end -1.551 1.475)
			(stroke
				(width 0.15)
				(type solid)
			)
			(layer "F.Fab")
		)
		(fp_rect
			(start -1.72 -1.5)
			(end 1.719 1.499)
			(stroke
				(width 0.15)
				(type solid)
			)
			(fill no)
			(layer "F.Fab")
		)
		(fp_text user "${REFERENCE}"
			(at -2.665 4.45 0)
			(layer "F.Fab")
			(effects
				(font
					(size 0.7 0.7)
					(thickness 0.15)
				)
				(justify left bottom)
			)
		)
		(fp_text user "License: Apache-2.0"
			(at -2.665 5.65 0)
			(layer "F.Fab")
			(effects
				(font
					(size 0.7 0.7)
					(thickness 0.15)
				)
				(justify left bottom)
			)
		)
		(fp_text user "Author: Antmicro"
			(at -2.665 6.85 0)
			(layer "F.Fab")
			(effects
				(font
					(size 0.7 0.7)
					(thickness 0.15)
				)
				(justify left bottom)
			)
		)
		(pad "1" smd roundrect
			(at -1.551 0)
			(size 1.2 2.2)
			(layers "F.Cu" "F.Mask" "F.Paste")
			(roundrect_rratio 0.1)
			(net 47 "+1V05")
			(pintype "passive")
		)
		(pad "2" smd roundrect
			(at 1.55 0)
			(size 1.2 2.2)
			(layers "F.Cu" "F.Mask" "F.Paste")
			(roundrect_rratio 0.1)
			(net 417 "GND")
			(pintype "passive")
		)
	)
	(footprint "antmicro-footprints:TP_SMD_0.75mm"
		(layer "F.Cu")
		(at 223 150.5)
		(property "Reference" "TP14"
			(at 12.93 5.49 90)
			(layer "F.SilkS")
			(hide yes)
			(effects
				(font
					(size 0.7 0.7)
					(thickness 0.15)
				)
				(justify left bottom)
			)
		)
		(property "Value" "TP_0.75mm_SMD"
			(at 0 1.2 0)
			(layer "F.Fab")
			(hide yes)
			(effects
				(font
					(size 0.7 0.7)
					(thickness 0.15)
				)
				(justify left bottom)
			)
		)
		(property "Description" "SMT test point"
			(at 0 0 0)
			(layer "F.Fab")
			(hide yes)
			(effects
				(font
					(size 1.27 1.27)
					(thickness 0.15)
				)
			)
		)
		(property "Author" "Antmicro"
			(at 0 0 0)
			(layer "F.Fab")
			(hide yes)
			(effects
				(font
					(size 1 1)
					(thickness 0.15)
				)
			)
		)
		(property "License" "Apache-2.0"
			(at 0 0 0)
			(layer "F.Fab")
			(hide yes)
			(effects
				(font
					(size 1 1)
					(thickness 0.15)
				)
			)
		)
		(property "MPN" ""
			(at 0 0 0)
			(layer "F.Fab")
			(hide yes)
			(effects
				(font
					(size 1 1)
					(thickness 0.15)
				)
			)
		)
		(property "Manufacturer" ""
			(at 0 0 0)
			(layer "F.Fab")
			(hide yes)
			(effects
				(font
					(size 1 1)
					(thickness 0.15)
				)
			)
		)
		(property "Public" "False"
			(at 0 0 0)
			(layer "F.Fab")
			(hide yes)
			(effects
				(font
					(size 1 1)
					(thickness 0.15)
				)
			)
		)
		(sheetname "/WiFi_Bluetooth/")
		(sheetfile "wifi_bt.kicad_sch")
		(attr exclude_from_pos_files exclude_from_bom)
		(fp_circle
			(center 0 0)
			(end 0.475 0)
			(stroke
				(width 0.05)
				(type default)
			)
			(fill no)
			(layer "F.CrtYd")
		)
		(fp_text user "${REFERENCE}"
			(at -0.4 2.7 0)
			(layer "F.Fab")
			(effects
				(font
					(size 0.7 0.7)
					(thickness 0.15)
				)
				(justify left bottom)
			)
		)
		(fp_text user "License: Apache-2.0"
			(at -0.4 5.101 0)
			(layer "F.Fab")
			(effects
				(font
					(size 0.7 0.7)
					(thickness 0.15)
				)
				(justify left bottom)
			)
		)
		(fp_text user "Author: Antmicro"
			(at -0.4 3.901 0)
			(layer "F.Fab")
			(effects
				(font
					(size 0.7 0.7)
					(thickness 0.15)
				)
				(justify left bottom)
			)
		)
		(pad "1" smd circle
			(at 0 0)
			(size 0.75 0.75)
			(layers "F.Cu" "F.Mask")
			(net 508 "Net-(U26A-BT_PCM_CLK)")
			(pinfunction "1")
			(pintype "passive")
		)
	)
)
